(kicad_pcb
	(version 20260206)
	(generator "pcbnew")
	(generator_version "10.0")
	(general
		(thickness 1.6)
		(legacy_teardrops no)
	)
	(paper "A4")
	(title_block
		(title "panther-plus-userver — 13130-1b_20150205.brd")
		(comment 1 "Honey Badger (Wiwynn) / footprint 624 of 1509 (DIMM4), pads 135-141 of 210")
	)
	(layers
		(0 "F.Cu" signal "TOP")
		(4 "In1.Cu" signal "L2")
		(6 "In2.Cu" signal "L3")
		(8 "In3.Cu" signal "L4")
		(10 "In4.Cu" signal "L5")
		(12 "In5.Cu" signal "L6")
		(14 "In6.Cu" signal "L7")
		(16 "In7.Cu" signal "L8")
		(18 "In8.Cu" signal "L9")
		(20 "In9.Cu" signal "L10")
		(22 "In10.Cu" signal "L11")
		(2 "B.Cu" signal "BOTTOM")
		(9 "F.Adhes" user "F.Adhesive")
		(11 "B.Adhes" user "B.Adhesive")
		(13 "F.Paste" user "Package Geometry/Pastemask Top")
		(15 "B.Paste" user "Package Geometry/Pastemask Bottom")
		(5 "F.SilkS" user "Ref Des/Silkscreen Top")
		(7 "B.SilkS" user "Ref Des/Silkscreen Bottom")
		(1 "F.Mask" user "Board Geometry/Soldermask Top")
		(3 "B.Mask" user "Board Geometry/Soldermask Bottom")
		(17 "Dwgs.User" user "User.Drawings")
		(19 "Cmts.User" user "User.Comments")
		(21 "Eco1.User" user "User.Eco1")
		(23 "Eco2.User" user "User.Eco2")
		(25 "Edge.Cuts" user "Board Geometry/Outline")
		(27 "Margin" user)
		(31 "F.CrtYd" user "Package Geometry/Place Bound Top")
		(29 "B.CrtYd" user "Package Geometry/Place Bound Bottom")
		(35 "F.Fab" user "Ref Des/Assembly Top")
		(33 "B.Fab" user "Ref Des/Assembly Bottom")
	)
	(footprint ""
		(layer "F.Cu")
		(at 159.999934 -5.790692)
		(property "Reference" "DIMM4"
			(at 0 0 0)
			(layer "F.SilkS")
			(hide yes)
			(effects
				(font
					(size 1.27 1.27)
				)
			)
		)
		(property "Value" "DDR3-204P-174-COLAY-1-GP"
			(at -40.682164 -17.468088 0)
			(unlocked yes)
			(layer "F.Fab")
			(hide yes)
			(effects
				(font
					(size 1.016 1.016)
					(thickness 0.1524)
				)
			)
		)
		(property "Device Type" "AS0A626-H8SN-7H-COLAY-1"
			(at -40.682164 -18.992088 0)
			(unlocked yes)
			(layer "F.Fab")
			(hide yes)
			(effects
				(font
					(size 1.016 1.016)
					(thickness 0.1524)
				)
			)
		)
		(duplicate_pad_numbers_are_jumpers no)
		(pad "133" smd custom
			(at 10.349992 4.106672)
			(size 0.1143 0.1143)
			(layers "F.Cu" "F.Mask" "F.Paste")
			(net "M_B_DQ36")
			(options
				(clearance outline)
				(anchor circle)
			)
			(primitives
				(gr_poly
					(pts
						(xy 0 0.9017) (xy -0.03175 0.89916) (xy -0.0635 0.889) (xy -0.09144 0.87376) (xy -0.11684 0.85344)
						(xy -0.13716 0.82804) (xy -0.1524 0.8001) (xy -0.16256 0.76835) (xy -0.1651 0.7366) (xy -0.1651 -0.13462)
						(xy -0.17272 -0.14224) (xy -0.19812 -0.1778) (xy -0.2032 -0.18796) (xy -0.20701 -0.19685) (xy -0.21209 -0.20701)
						(xy -0.2159 -0.21717) (xy -0.21844 -0.22733) (xy -0.22225 -0.23876) (xy -0.22352 -0.24892) (xy -0.22606 -0.25908)
						(xy -0.22733 -0.27051) (xy -0.22733 -0.28067) (xy -0.2286 -0.2921) (xy -0.22733 -0.30353) (xy -0.22733 -0.31369)
						(xy -0.22606 -0.32512) (xy -0.22352 -0.33528) (xy -0.22225 -0.34544) (xy -0.21844 -0.35687) (xy -0.2159 -0.36703)
						(xy -0.21209 -0.37719) (xy -0.20701 -0.38735) (xy -0.2032 -0.39624) (xy -0.19812 -0.4064) (xy -0.17272 -0.44196)
						(xy -0.1651 -0.44958) (xy -0.1651 -0.7366) (xy -0.16256 -0.76835) (xy -0.1524 -0.8001) (xy -0.13716 -0.82804)
						(xy -0.11684 -0.85344) (xy -0.09144 -0.87376) (xy -0.0635 -0.889) (xy -0.03175 -0.89916) (xy 0 -0.9017)
						(xy 0.03175 -0.89916) (xy 0.0635 -0.889) (xy 0.09144 -0.87376) (xy 0.11684 -0.85344) (xy 0.13716 -0.82804)
						(xy 0.1524 -0.8001) (xy 0.16256 -0.76835) (xy 0.1651 -0.7366) (xy 0.1651 -0.44958) (xy 0.17272 -0.44196)
						(xy 0.19812 -0.4064) (xy 0.2032 -0.39624) (xy 0.20701 -0.38735) (xy 0.21209 -0.37719) (xy 0.2159 -0.36703)
						(xy 0.21844 -0.35687) (xy 0.22225 -0.34544) (xy 0.22352 -0.33528) (xy 0.22606 -0.32512) (xy 0.22733 -0.31369)
						(xy 0.22733 -0.30353) (xy 0.2286 -0.2921) (xy 0.22733 -0.28067) (xy 0.22733 -0.27051) (xy 0.22606 -0.25908)
						(xy 0.22352 -0.24892) (xy 0.22225 -0.23876) (xy 0.21844 -0.22733) (xy 0.2159 -0.21717) (xy 0.21209 -0.20701)
						(xy 0.20701 -0.19685) (xy 0.2032 -0.18796) (xy 0.19812 -0.1778) (xy 0.17272 -0.14224) (xy 0.1651 -0.13462)
						(xy 0.1651 0.7366) (xy 0.16256 0.76835) (xy 0.1524 0.8001) (xy 0.13716 0.82804) (xy 0.11684 0.85344)
						(xy 0.09144 0.87376) (xy 0.0635 0.889) (xy 0.03175 0.89916)
					)
					(width 0)
					(fill yes)
				)
			)
		)
		(pad "134" smd custom
			(at 10.649966 -4.106672)
			(size 0.1143 0.1143)
			(layers "F.Cu" "F.Mask" "F.Paste")
			(net "M_B_DQ32")
			(options
				(clearance outline)
				(anchor circle)
			)
			(primitives
				(gr_poly
					(pts
						(xy 0 0.9017) (xy -0.03175 0.89916) (xy -0.0635 0.889) (xy -0.09144 0.87376) (xy -0.11684 0.85344)
						(xy -0.13716 0.82804) (xy -0.1524 0.8001) (xy -0.16256 0.76835) (xy -0.1651 0.7366) (xy -0.1651 0.44958)
						(xy -0.17272 0.44196) (xy -0.19812 0.4064) (xy -0.2032 0.39624) (xy -0.20701 0.38735) (xy -0.21209 0.37719)
						(xy -0.2159 0.36703) (xy -0.21844 0.35687) (xy -0.22225 0.34544) (xy -0.22352 0.33528) (xy -0.22606 0.32512)
						(xy -0.22733 0.31369) (xy -0.22733 0.30353) (xy -0.2286 0.2921) (xy -0.22733 0.28067) (xy -0.22733 0.27051)
						(xy -0.22606 0.25908) (xy -0.22352 0.24892) (xy -0.22225 0.23876) (xy -0.21844 0.22733) (xy -0.2159 0.21717)
						(xy -0.21209 0.20701) (xy -0.20701 0.19685) (xy -0.2032 0.18796) (xy -0.19812 0.1778) (xy -0.17272 0.14224)
						(xy -0.1651 0.13462) (xy -0.1651 -0.7366) (xy -0.16256 -0.76835) (xy -0.1524 -0.8001) (xy -0.13716 -0.82804)
						(xy -0.11684 -0.85344) (xy -0.09144 -0.87376) (xy -0.0635 -0.889) (xy -0.03175 -0.89916) (xy 0 -0.9017)
						(xy 0.03175 -0.89916) (xy 0.0635 -0.889) (xy 0.09144 -0.87376) (xy 0.11684 -0.85344) (xy 0.13716 -0.82804)
						(xy 0.1524 -0.8001) (xy 0.16256 -0.76835) (xy 0.1651 -0.7366) (xy 0.1651 0.13462) (xy 0.17272 0.14224)
						(xy 0.19812 0.1778) (xy 0.2032 0.18796) (xy 0.20701 0.19685) (xy 0.21209 0.20701) (xy 0.2159 0.21717)
						(xy 0.21844 0.22733) (xy 0.22225 0.23876) (xy 0.22352 0.24892) (xy 0.22606 0.25908) (xy 0.22733 0.27051)
						(xy 0.22733 0.28067) (xy 0.2286 0.2921) (xy 0.22733 0.30353) (xy 0.22733 0.31369) (xy 0.22606 0.32512)
						(xy 0.22352 0.33528) (xy 0.22225 0.34544) (xy 0.21844 0.35687) (xy 0.2159 0.36703) (xy 0.21209 0.37719)
						(xy 0.20701 0.38735) (xy 0.2032 0.39624) (xy 0.19812 0.4064) (xy 0.17272 0.44196) (xy 0.1651 0.44958)
						(xy 0.1651 0.7366) (xy 0.16256 0.76835) (xy 0.1524 0.8001) (xy 0.13716 0.82804) (xy 0.11684 0.85344)
						(xy 0.09144 0.87376) (xy 0.0635 0.889) (xy 0.03175 0.89916)
					)
					(width 0)
					(fill yes)
				)
			)
		)
		(pad "135" smd custom
			(at 10.94994 4.106672)
			(size 0.1143 0.1143)
			(layers "F.Cu" "F.Mask" "F.Paste")
			(net "M_B_DQ37")
			(options
				(clearance outline)
				(anchor circle)
			)
			(primitives
				(gr_poly
					(pts
						(xy 0 0.9017) (xy -0.03175 0.89916) (xy -0.0635 0.889) (xy -0.09144 0.87376) (xy -0.11684 0.85344)
						(xy -0.13716 0.82804) (xy -0.1524 0.8001) (xy -0.16256 0.76835) (xy -0.1651 0.7366) (xy -0.1651 0.11938)
						(xy -0.17272 0.11176) (xy -0.19812 0.0762) (xy -0.2032 0.06604) (xy -0.20701 0.05715) (xy -0.21209 0.04699)
						(xy -0.2159 0.03683) (xy -0.21844 0.02667) (xy -0.22225 0.01524) (xy -0.22352 0.00508) (xy -0.22606 -0.00508)
						(xy -0.22733 -0.01651) (xy -0.22733 -0.02667) (xy -0.2286 -0.0381) (xy -0.22733 -0.04953) (xy -0.22733 -0.05969)
						(xy -0.22606 -0.07112) (xy -0.22352 -0.08128) (xy -0.22225 -0.09144) (xy -0.21844 -0.10287) (xy -0.2159 -0.11303)
						(xy -0.21209 -0.12319) (xy -0.20701 -0.13335) (xy -0.2032 -0.14224) (xy -0.19812 -0.1524) (xy -0.17272 -0.18796)
						(xy -0.1651 -0.19558) (xy -0.1651 -0.7366) (xy -0.16256 -0.76835) (xy -0.1524 -0.8001) (xy -0.13716 -0.82804)
						(xy -0.11684 -0.85344) (xy -0.09144 -0.87376) (xy -0.0635 -0.889) (xy -0.03175 -0.89916) (xy 0 -0.9017)
						(xy 0.03175 -0.89916) (xy 0.0635 -0.889) (xy 0.09144 -0.87376) (xy 0.11684 -0.85344) (xy 0.13716 -0.82804)
						(xy 0.1524 -0.8001) (xy 0.16256 -0.76835) (xy 0.1651 -0.7366) (xy 0.1651 -0.19685) (xy 0.17272 -0.18923)
						(xy 0.17907 -0.18034) (xy 0.18669 -0.17145) (xy 0.19177 -0.16256) (xy 0.19812 -0.15367) (xy 0.20828 -0.13335)
						(xy 0.21971 -0.10287) (xy 0.22225 -0.09271) (xy 0.22479 -0.08128) (xy 0.22606 -0.07112) (xy 0.2286 -0.05969)
						(xy 0.2286 -0.01651) (xy 0.22606 -0.00508) (xy 0.22479 0.00508) (xy 0.22225 0.01651) (xy 0.21971 0.02667)
						(xy 0.20828 0.05715) (xy 0.19812 0.07747) (xy 0.19177 0.08636) (xy 0.18669 0.09525) (xy 0.17907 0.10414)
						(xy 0.17272 0.11303) (xy 0.1651 0.12065) (xy 0.1651 0.7366) (xy 0.16256 0.76835) (xy 0.1524 0.8001)
						(xy 0.13716 0.82804) (xy 0.11684 0.85344) (xy 0.09144 0.87376) (xy 0.0635 0.889) (xy 0.03175 0.89916)
					)
					(width 0)
					(fill yes)
				)
			)
		)
		(pad "136" smd custom
			(at 11.249914 -4.106672)
			(size 0.1143 0.1143)
			(layers "F.Cu" "F.Mask" "F.Paste")
			(net "M_B_DQ33")
			(options
				(clearance outline)
				(anchor circle)
			)
			(primitives
				(gr_poly
					(pts
						(xy 0 0.9017) (xy -0.03175 0.89916) (xy -0.0635 0.889) (xy -0.09144 0.87376) (xy -0.11684 0.85344)
						(xy -0.13716 0.82804) (xy -0.1524 0.8001) (xy -0.16256 0.76835) (xy -0.1651 0.7366) (xy -0.1651 0.19685)
						(xy -0.17272 0.18923) (xy -0.17907 0.18034) (xy -0.18669 0.17145) (xy -0.19177 0.16256) (xy -0.19812 0.15367)
						(xy -0.20828 0.13335) (xy -0.21971 0.10287) (xy -0.22225 0.09271) (xy -0.22479 0.08128) (xy -0.22606 0.07112)
						(xy -0.2286 0.05969) (xy -0.2286 0.01651) (xy -0.22606 0.00508) (xy -0.22479 -0.00508) (xy -0.22225 -0.01651)
						(xy -0.21971 -0.02667) (xy -0.20828 -0.05715) (xy -0.19812 -0.07747) (xy -0.19177 -0.08636) (xy -0.18669 -0.09525)
						(xy -0.17907 -0.10414) (xy -0.17272 -0.11303) (xy -0.1651 -0.12065) (xy -0.1651 -0.7366) (xy -0.16256 -0.76835)
						(xy -0.1524 -0.8001) (xy -0.13716 -0.82804) (xy -0.11684 -0.85344) (xy -0.09144 -0.87376) (xy -0.0635 -0.889)
						(xy -0.03175 -0.89916) (xy 0 -0.9017) (xy 0.03175 -0.89916) (xy 0.0635 -0.889) (xy 0.09144 -0.87376)
						(xy 0.11684 -0.85344) (xy 0.13716 -0.82804) (xy 0.1524 -0.8001) (xy 0.16256 -0.76835) (xy 0.1651 -0.7366)
						(xy 0.1651 -0.11938) (xy 0.17272 -0.11176) (xy 0.19812 -0.0762) (xy 0.2032 -0.06604) (xy 0.20701 -0.05715)
						(xy 0.21209 -0.04699) (xy 0.2159 -0.03683) (xy 0.21844 -0.02667) (xy 0.22225 -0.01524) (xy 0.22352 -0.00508)
						(xy 0.22606 0.00508) (xy 0.22733 0.01651) (xy 0.22733 0.02667) (xy 0.2286 0.0381) (xy 0.22733 0.04953)
						(xy 0.22733 0.05969) (xy 0.22606 0.07112) (xy 0.22352 0.08128) (xy 0.22225 0.09144) (xy 0.21844 0.10287)
						(xy 0.2159 0.11303) (xy 0.21209 0.12319) (xy 0.20701 0.13335) (xy 0.2032 0.14224) (xy 0.19812 0.1524)
						(xy 0.17272 0.18796) (xy 0.1651 0.19558) (xy 0.1651 0.7366) (xy 0.16256 0.76835) (xy 0.1524 0.8001)
						(xy 0.13716 0.82804) (xy 0.11684 0.85344) (xy 0.09144 0.87376) (xy 0.0635 0.889) (xy 0.03175 0.89916)
					)
					(width 0)
					(fill yes)
				)
			)
		)
		(pad "137" smd custom
			(at 11.549888 4.106672)
			(size 0.1143 0.1143)
			(layers "F.Cu" "F.Mask" "F.Paste")
			(net "GND")
			(options
				(clearance outline)
				(anchor circle)
			)
			(primitives
				(gr_poly
					(pts
						(xy 0 0.9017) (xy -0.03175 0.89916) (xy -0.0635 0.889) (xy -0.09144 0.87376) (xy -0.11684 0.85344)
						(xy -0.13716 0.82804) (xy -0.1524 0.8001) (xy -0.16256 0.76835) (xy -0.1651 0.7366) (xy -0.1651 -0.13462)
						(xy -0.17272 -0.14224) (xy -0.19812 -0.1778) (xy -0.2032 -0.18796) (xy -0.20701 -0.19685) (xy -0.21209 -0.20701)
						(xy -0.2159 -0.21717) (xy -0.21844 -0.22733) (xy -0.22225 -0.23876) (xy -0.22352 -0.24892) (xy -0.22606 -0.25908)
						(xy -0.22733 -0.27051) (xy -0.22733 -0.28067) (xy -0.2286 -0.2921) (xy -0.22733 -0.30353) (xy -0.22733 -0.31369)
						(xy -0.22606 -0.32512) (xy -0.22352 -0.33528) (xy -0.22225 -0.34544) (xy -0.21844 -0.35687) (xy -0.2159 -0.36703)
						(xy -0.21209 -0.37719) (xy -0.20701 -0.38735) (xy -0.2032 -0.39624) (xy -0.19812 -0.4064) (xy -0.17272 -0.44196)
						(xy -0.1651 -0.44958) (xy -0.1651 -0.7366) (xy -0.16256 -0.76835) (xy -0.1524 -0.8001) (xy -0.13716 -0.82804)
						(xy -0.11684 -0.85344) (xy -0.09144 -0.87376) (xy -0.0635 -0.889) (xy -0.03175 -0.89916) (xy 0 -0.9017)
						(xy 0.03175 -0.89916) (xy 0.0635 -0.889) (xy 0.09144 -0.87376) (xy 0.11684 -0.85344) (xy 0.13716 -0.82804)
						(xy 0.1524 -0.8001) (xy 0.16256 -0.76835) (xy 0.1651 -0.7366) (xy 0.1651 -0.44958) (xy 0.17272 -0.44196)
						(xy 0.19812 -0.4064) (xy 0.2032 -0.39624) (xy 0.20701 -0.38735) (xy 0.21209 -0.37719) (xy 0.2159 -0.36703)
						(xy 0.21844 -0.35687) (xy 0.22225 -0.34544) (xy 0.22352 -0.33528) (xy 0.22606 -0.32512) (xy 0.22733 -0.31369)
						(xy 0.22733 -0.30353) (xy 0.2286 -0.2921) (xy 0.22733 -0.28067) (xy 0.22733 -0.27051) (xy 0.22606 -0.25908)
						(xy 0.22352 -0.24892) (xy 0.22225 -0.23876) (xy 0.21844 -0.22733) (xy 0.2159 -0.21717) (xy 0.21209 -0.20701)
						(xy 0.20701 -0.19685) (xy 0.2032 -0.18796) (xy 0.19812 -0.1778) (xy 0.17272 -0.14224) (xy 0.1651 -0.13462)
						(xy 0.1651 0.7366) (xy 0.16256 0.76835) (xy 0.1524 0.8001) (xy 0.13716 0.82804) (xy 0.11684 0.85344)
						(xy 0.09144 0.87376) (xy 0.0635 0.889) (xy 0.03175 0.89916)
					)
					(width 0)
					(fill yes)
				)
			)
		)
		(pad "138" smd custom
			(at 11.850116 -4.106672)
			(size 0.1143 0.1143)
			(layers "F.Cu" "F.Mask" "F.Paste")
			(net "GND")
			(options
				(clearance outline)
				(anchor circle)
			)
			(primitives
				(gr_poly
					(pts
						(xy 0 0.9017) (xy -0.03175 0.89916) (xy -0.0635 0.889) (xy -0.09144 0.87376) (xy -0.11684 0.85344)
						(xy -0.13716 0.82804) (xy -0.1524 0.8001) (xy -0.16256 0.76835) (xy -0.1651 0.7366) (xy -0.1651 0.44958)
						(xy -0.17272 0.44196) (xy -0.19812 0.4064) (xy -0.2032 0.39624) (xy -0.20701 0.38735) (xy -0.21209 0.37719)
						(xy -0.2159 0.36703) (xy -0.21844 0.35687) (xy -0.22225 0.34544) (xy -0.22352 0.33528) (xy -0.22606 0.32512)
						(xy -0.22733 0.31369) (xy -0.22733 0.30353) (xy -0.2286 0.2921) (xy -0.22733 0.28067) (xy -0.22733 0.27051)
						(xy -0.22606 0.25908) (xy -0.22352 0.24892) (xy -0.22225 0.23876) (xy -0.21844 0.22733) (xy -0.2159 0.21717)
						(xy -0.21209 0.20701) (xy -0.20701 0.19685) (xy -0.2032 0.18796) (xy -0.19812 0.1778) (xy -0.17272 0.14224)
						(xy -0.1651 0.13462) (xy -0.1651 -0.7366) (xy -0.16256 -0.76835) (xy -0.1524 -0.8001) (xy -0.13716 -0.82804)
						(xy -0.11684 -0.85344) (xy -0.09144 -0.87376) (xy -0.0635 -0.889) (xy -0.03175 -0.89916) (xy 0 -0.9017)
						(xy 0.03175 -0.89916) (xy 0.0635 -0.889) (xy 0.09144 -0.87376) (xy 0.11684 -0.85344) (xy 0.13716 -0.82804)
						(xy 0.1524 -0.8001) (xy 0.16256 -0.76835) (xy 0.1651 -0.7366) (xy 0.1651 0.13462) (xy 0.17272 0.14224)
						(xy 0.19812 0.1778) (xy 0.2032 0.18796) (xy 0.20701 0.19685) (xy 0.21209 0.20701) (xy 0.2159 0.21717)
						(xy 0.21844 0.22733) (xy 0.22225 0.23876) (xy 0.22352 0.24892) (xy 0.22606 0.25908) (xy 0.22733 0.27051)
						(xy 0.22733 0.28067) (xy 0.2286 0.2921) (xy 0.22733 0.30353) (xy 0.22733 0.31369) (xy 0.22606 0.32512)
						(xy 0.22352 0.33528) (xy 0.22225 0.34544) (xy 0.21844 0.35687) (xy 0.2159 0.36703) (xy 0.21209 0.37719)
						(xy 0.20701 0.38735) (xy 0.2032 0.39624) (xy 0.19812 0.4064) (xy 0.17272 0.44196) (xy 0.1651 0.44958)
						(xy 0.1651 0.7366) (xy 0.16256 0.76835) (xy 0.1524 0.8001) (xy 0.13716 0.82804) (xy 0.11684 0.85344)
						(xy 0.09144 0.87376) (xy 0.0635 0.889) (xy 0.03175 0.89916)
					)
					(width 0)
					(fill yes)
				)
			)
		)
		(pad "139" smd custom
			(at 12.15009 4.106672)
			(size 0.1143 0.1143)
			(layers "F.Cu" "F.Mask" "F.Paste")
			(net "M_B_DQS_DN4")
			(options
				(clearance outline)
				(anchor circle)
			)
			(primitives
				(gr_poly
					(pts
						(xy 0 0.9017) (xy -0.03175 0.89916) (xy -0.0635 0.889) (xy -0.09144 0.87376) (xy -0.11684 0.85344)
						(xy -0.13716 0.82804) (xy -0.1524 0.8001) (xy -0.16256 0.76835) (xy -0.1651 0.7366) (xy -0.1651 0.11938)
						(xy -0.17272 0.11176) (xy -0.19812 0.0762) (xy -0.2032 0.06604) (xy -0.20701 0.05715) (xy -0.21209 0.04699)
						(xy -0.2159 0.03683) (xy -0.21844 0.02667) (xy -0.22225 0.01524) (xy -0.22352 0.00508) (xy -0.22606 -0.00508)
						(xy -0.22733 -0.01651) (xy -0.22733 -0.02667) (xy -0.2286 -0.0381) (xy -0.22733 -0.04953) (xy -0.22733 -0.05969)
						(xy -0.22606 -0.07112) (xy -0.22352 -0.08128) (xy -0.22225 -0.09144) (xy -0.21844 -0.10287) (xy -0.2159 -0.11303)
						(xy -0.21209 -0.12319) (xy -0.20701 -0.13335) (xy -0.2032 -0.14224) (xy -0.19812 -0.1524) (xy -0.17272 -0.18796)
						(xy -0.1651 -0.19558) (xy -0.1651 -0.7366) (xy -0.16256 -0.76835) (xy -0.1524 -0.8001) (xy -0.13716 -0.82804)
						(xy -0.11684 -0.85344) (xy -0.09144 -0.87376) (xy -0.0635 -0.889) (xy -0.03175 -0.89916) (xy 0 -0.9017)
						(xy 0.03175 -0.89916) (xy 0.0635 -0.889) (xy 0.09144 -0.87376) (xy 0.11684 -0.85344) (xy 0.13716 -0.82804)
						(xy 0.1524 -0.8001) (xy 0.16256 -0.76835) (xy 0.1651 -0.7366) (xy 0.1651 -0.19685) (xy 0.17272 -0.18923)
						(xy 0.17907 -0.18034) (xy 0.18669 -0.17145) (xy 0.19177 -0.16256) (xy 0.19812 -0.15367) (xy 0.20828 -0.13335)
						(xy 0.21971 -0.10287) (xy 0.22225 -0.09271) (xy 0.22479 -0.08128) (xy 0.22606 -0.07112) (xy 0.2286 -0.05969)
						(xy 0.2286 -0.01651) (xy 0.22606 -0.00508) (xy 0.22479 0.00508) (xy 0.22225 0.01651) (xy 0.21971 0.02667)
						(xy 0.20828 0.05715) (xy 0.19812 0.07747) (xy 0.19177 0.08636) (xy 0.18669 0.09525) (xy 0.17907 0.10414)
						(xy 0.17272 0.11303) (xy 0.1651 0.12065) (xy 0.1651 0.7366) (xy 0.16256 0.76835) (xy 0.1524 0.8001)
						(xy 0.13716 0.82804) (xy 0.11684 0.85344) (xy 0.09144 0.87376) (xy 0.0635 0.889) (xy 0.03175 0.89916)
					)
					(width 0)
					(fill yes)
				)
			)
		)
	)
)
